(kicad_pcb
	(version 20241229)
	(generator "pcbnew")
	(generator_version "9.0")
	(general
		(thickness 1.62)
		(legacy_teardrops no)
	)
	(paper "A4")
	(title_block
		(title "OCuLink to 10GbE adapter")
		(date "2026-02-23")
		(rev "1.1.0")
		(company "Antmicro Ltd")
		(comment 1 "www.antmicro.com")
		(comment 9 "footprints 457-461 of 510")
	)
	(layers
		(0 "F.Cu" signal)
		(4 "In1.Cu" signal)
		(6 "In2.Cu" signal)
		(8 "In3.Cu" signal)
		(10 "In4.Cu" signal)
		(12 "In5.Cu" signal)
		(14 "In6.Cu" signal)
		(2 "B.Cu" signal)
		(9 "F.Adhes" user "F.Adhesive")
		(11 "B.Adhes" user "B.Adhesive")
		(13 "F.Paste" user)
		(15 "B.Paste" user)
		(5 "F.SilkS" user "F.Silkscreen")
		(7 "B.SilkS" user "B.Silkscreen")
		(1 "F.Mask" user)
		(3 "B.Mask" user)
		(17 "Dwgs.User" user "User.Drawings")
		(19 "Cmts.User" user "User.Comments")
		(21 "Eco1.User" user "User.Eco1")
		(23 "Eco2.User" user "User.Eco2")
		(25 "Edge.Cuts" user)
		(27 "Margin" user)
		(31 "F.CrtYd" user "F.Courtyard")
		(29 "B.CrtYd" user "B.Courtyard")
		(35 "F.Fab" user)
		(33 "B.Fab" user)
	)
	(footprint "antmicro-footprints:C_0402_1005Metric"
		(layer "B.Cu")
		(at 85.8 108.35 180)
		(descr "Capacitor SMD 0402")
		(tags "capacitor SMD 0402")
		(property "Reference" "C176"
			(at -1.72 -1.3 0)
			(layer "B.SilkS")
			(effects
				(font
					(size 0.7 0.7)
					(thickness 0.15)
				)
				(justify left bottom mirror)
			)
		)
		(property "Value" "C_1u_25V_0402"
			(at -1.022927 -2.155213 0)
			(layer "B.Fab")
			(hide yes)
			(effects
				(font
					(size 0.7 0.7)
					(thickness 0.15)
				)
				(justify left bottom mirror)
			)
		)
		(property "Datasheet" "https://www.murata.com/products/productdetail?partno=GRM155R61E105KE11%23"
			(at 0 0 0)
			(layer "B.Fab")
			(hide yes)
			(effects
				(font
					(size 1.27 1.27)
					(thickness 0.15)
				)
				(justify mirror)
			)
		)
		(property "Description" "SMD Multilayer Ceramic Capacitor, 1 µF, 25 V, 0402 [1005 Metric], ± 10%, X5R, GRM Series"
			(at 0 0 0)
			(layer "B.Fab")
			(hide yes)
			(effects
				(font
					(size 1.27 1.27)
					(thickness 0.15)
				)
				(justify mirror)
			)
		)
		(property "MPN" "GRM155R61E105KE11J"
			(at 0 0 180)
			(unlocked yes)
			(layer "B.Fab")
			(hide yes)
			(effects
				(font
					(size 1 1)
					(thickness 0.15)
				)
				(justify mirror)
			)
		)
		(property "Manufacturer" "Murata"
			(at 0 0 180)
			(unlocked yes)
			(layer "B.Fab")
			(hide yes)
			(effects
				(font
					(size 1 1)
					(thickness 0.15)
				)
				(justify mirror)
			)
		)
		(property "License" "Apache-2.0"
			(at 0 0 180)
			(unlocked yes)
			(layer "B.Fab")
			(hide yes)
			(effects
				(font
					(size 1 1)
					(thickness 0.15)
				)
				(justify mirror)
			)
		)
		(property "Author" "Antmicro"
			(at 0 0 180)
			(unlocked yes)
			(layer "B.Fab")
			(hide yes)
			(effects
				(font
					(size 1 1)
					(thickness 0.15)
				)
				(justify mirror)
			)
		)
		(property "Val" "1u"
			(at 0 0 180)
			(unlocked yes)
			(layer "B.Fab")
			(hide yes)
			(effects
				(font
					(size 1 1)
					(thickness 0.15)
				)
				(justify mirror)
			)
		)
		(property "Voltage" "25V"
			(at 0 0 180)
			(unlocked yes)
			(layer "B.Fab")
			(hide yes)
			(effects
				(font
					(size 1 1)
					(thickness 0.15)
				)
				(justify mirror)
			)
		)
		(property "Dielectric" "X5R"
			(at 0 0 180)
			(unlocked yes)
			(layer "B.Fab")
			(hide yes)
			(effects
				(font
					(size 1 1)
					(thickness 0.15)
				)
				(justify mirror)
			)
		)
		(sheetname "/X710-AT2 power/")
		(sheetfile "x710-at2-power.kicad_sch")
		(attr smd)
		(fp_rect
			(start -0.925 0.47)
			(end 0.925 -0.47)
			(stroke
				(width 0.05)
				(type default)
			)
			(fill no)
			(layer "B.CrtYd")
		)
		(fp_line
			(start 0.504 0.25)
			(end 0.504 -0.248)
			(stroke
				(width 0.15)
				(type solid)
			)
			(layer "B.Fab")
		)
		(fp_line
			(start 0.504 -0.248)
			(end -0.494 -0.248)
			(stroke
				(width 0.15)
				(type solid)
			)
			(layer "B.Fab")
		)
		(fp_line
			(start -0.494 0.25)
			(end 0.504 0.25)
			(stroke
				(width 0.15)
				(type solid)
			)
			(layer "B.Fab")
		)
		(fp_line
			(start -0.494 -0.248)
			(end -0.494 0.25)
			(stroke
				(width 0.15)
				(type solid)
			)
			(layer "B.Fab")
		)
		(pad "1" smd roundrect
			(at -0.48 0 180)
			(size 0.59 0.64)
			(layers "B.Cu" "B.Mask" "B.Paste")
			(roundrect_rratio 0.25)
			(net 28 "GND")
			(pintype "passive")
		)
		(pad "2" smd roundrect
			(at 0.48 0 180)
			(size 0.59 0.64)
			(layers "B.Cu" "B.Mask" "B.Paste")
			(roundrect_rratio 0.25)
			(net 14 "P1_AVDDL")
			(pintype "passive")
		)
	)
	(footprint "antmicro-footprints:FB_0603_1608Metric"
		(layer "B.Cu")
		(at 73.1 105.45)
		(property "Reference" "FB7"
			(at -3.25 -0.41 0)
			(layer "B.SilkS")
			(effects
				(font
					(size 0.7 0.7)
					(thickness 0.15)
				)
				(justify right top mirror)
			)
		)
		(property "Value" "FB_470Z_1A_Murata-BLM18PG_0603"
			(at 0 -1.5 0)
			(layer "B.Fab")
			(hide yes)
			(effects
				(font
					(size 0.7 0.7)
					(thickness 0.15)
				)
				(justify right top mirror)
			)
		)
		(property "Datasheet" "https://www.murata.com/en-us/products/productdata/8796738650142/ENFA0003.pdf"
			(at 0 0 0)
			(layer "B.Fab")
			(hide yes)
			(effects
				(font
					(size 1.27 1.27)
					(thickness 0.15)
				)
				(justify mirror)
			)
		)
		(property "Description" "Ferrite Bead, 0603 [1608 Metric], 470 ohm, 1 A, BLM18P, 0.2 ohm, ± 25%, DC power line"
			(at 0 0 0)
			(layer "B.Fab")
			(hide yes)
			(effects
				(font
					(size 1.27 1.27)
					(thickness 0.15)
				)
				(justify mirror)
			)
		)
		(property "Val" "470Z/1A"
			(at 0 0 0)
			(unlocked yes)
			(layer "B.Fab")
			(hide yes)
			(effects
				(font
					(size 1 1)
					(thickness 0.15)
				)
				(justify mirror)
			)
		)
		(property "MPN" "BLM18PG471SN1D"
			(at 0 0 0)
			(unlocked yes)
			(layer "B.Fab")
			(hide yes)
			(effects
				(font
					(size 1 1)
					(thickness 0.15)
				)
				(justify mirror)
			)
		)
		(property "Manufacturer" "Murata"
			(at 0 0 0)
			(unlocked yes)
			(layer "B.Fab")
			(hide yes)
			(effects
				(font
					(size 1 1)
					(thickness 0.15)
				)
				(justify mirror)
			)
		)
		(property "Current" ""
			(at 0 0 0)
			(unlocked yes)
			(layer "B.Fab")
			(hide yes)
			(effects
				(font
					(size 1 1)
					(thickness 0.15)
				)
				(justify mirror)
			)
		)
		(property "Author" "Antmicro"
			(at 0 0 0)
			(unlocked yes)
			(layer "B.Fab")
			(hide yes)
			(effects
				(font
					(size 1 1)
					(thickness 0.15)
				)
				(justify mirror)
			)
		)
		(property "License" "Apache-2.0"
			(at 0 0 0)
			(unlocked yes)
			(layer "B.Fab")
			(hide yes)
			(effects
				(font
					(size 1 1)
					(thickness 0.15)
				)
				(justify mirror)
			)
		)
		(sheetname "/X710-AT2 power/")
		(sheetfile "x710-at2-power.kicad_sch")
		(attr smd)
		(fp_line
			(start -0.15 -0.4)
			(end 0.15 -0.4)
			(stroke
				(width 0.15)
				(type solid)
			)
			(layer "B.SilkS")
		)
		(fp_line
			(start -0.15 0.4)
			(end 0.15 0.4)
			(stroke
				(width 0.15)
				(type solid)
			)
			(layer "B.SilkS")
		)
		(fp_rect
			(start -1.25 0.65)
			(end 1.25 -0.65)
			(stroke
				(width 0.05)
				(type solid)
			)
			(fill no)
			(layer "B.CrtYd")
		)
		(fp_line
			(start -0.803 -0.406)
			(end -0.803 0.408)
			(stroke
				(width 0.15)
				(type solid)
			)
			(layer "B.Fab")
		)
		(fp_line
			(start 0.8 -0.406)
			(end -0.803 -0.406)
			(stroke
				(width 0.15)
				(type solid)
			)
			(layer "B.Fab")
		)
		(fp_line
			(start 0.8 0.408)
			(end -0.803 0.408)
			(stroke
				(width 0.15)
				(type solid)
			)
			(layer "B.Fab")
		)
		(fp_line
			(start 0.8 0.408)
			(end 0.8 -0.406)
			(stroke
				(width 0.15)
				(type solid)
			)
			(layer "B.Fab")
		)
		(pad "1" smd roundrect
			(at -0.7 0)
			(size 0.8 1)
			(layers "B.Cu" "B.Mask" "B.Paste")
			(roundrect_rratio 0.2)
			(net 302 "+1V0")
			(pintype "passive")
		)
		(pad "2" smd roundrect
			(at 0.7 0)
			(size 0.8 1)
			(layers "B.Cu" "B.Mask" "B.Paste")
			(roundrect_rratio 0.2)
			(net 27 "PLL_VDD")
			(pintype "passive")
		)
	)
	(footprint "antmicro-footprints:C_0402_1005Metric"
		(layer "B.Cu")
		(at 83.3 127.1)
		(descr "Capacitor SMD 0402")
		(tags "capacitor SMD 0402")
		(property "Reference" "C51"
			(at -0.85 0.45 0)
			(layer "B.SilkS")
			(effects
				(font
					(size 0.7 0.7)
					(thickness 0.15)
				)
				(justify left bottom mirror)
			)
		)
		(property "Value" "C_100n_0402"
			(at -1.022927 -2.155213 0)
			(layer "B.Fab")
			(hide yes)
			(effects
				(font
					(size 0.7 0.7)
					(thickness 0.15)
				)
				(justify right top mirror)
			)
		)
		(property "Datasheet" "https://www.murata.com/products/productdetail?partno=GRM155R61H104KE14%23"
			(at 0 0 0)
			(layer "B.Fab")
			(hide yes)
			(effects
				(font
					(size 1.27 1.27)
					(thickness 0.15)
				)
				(justify mirror)
			)
		)
		(property "Description" "SMD Multilayer Ceramic Capacitor, 0.1 µF, 50 V, 0402 [1005 Metric], ± 10%, X5R, GRM Series"
			(at 0 0 0)
			(layer "B.Fab")
			(hide yes)
			(effects
				(font
					(size 1.27 1.27)
					(thickness 0.15)
				)
				(justify mirror)
			)
		)
		(property "MPN" "GRM155R61H104KE14D"
			(at 0 0 0)
			(unlocked yes)
			(layer "B.Fab")
			(hide yes)
			(effects
				(font
					(size 1 1)
					(thickness 0.15)
				)
				(justify mirror)
			)
		)
		(property "Val" "100n"
			(at 0 0 0)
			(unlocked yes)
			(layer "B.Fab")
			(hide yes)
			(effects
				(font
					(size 1 1)
					(thickness 0.15)
				)
				(justify mirror)
			)
		)
		(property "Voltage" "50V"
			(at 0 0 0)
			(unlocked yes)
			(layer "B.Fab")
			(hide yes)
			(effects
				(font
					(size 1 1)
					(thickness 0.15)
				)
				(justify mirror)
			)
		)
		(property "Dielectric" "X5R"
			(at 0 0 0)
			(unlocked yes)
			(layer "B.Fab")
			(hide yes)
			(effects
				(font
					(size 1 1)
					(thickness 0.15)
				)
				(justify mirror)
			)
		)
		(property "Manufacturer" "Murata"
			(at 0 0 0)
			(unlocked yes)
			(layer "B.Fab")
			(hide yes)
			(effects
				(font
					(size 1 1)
					(thickness 0.15)
				)
				(justify mirror)
			)
		)
		(property "License" "Apache-2.0"
			(at 0 0 0)
			(unlocked yes)
			(layer "B.Fab")
			(hide yes)
			(effects
				(font
					(size 1 1)
					(thickness 0.15)
				)
				(justify mirror)
			)
		)
		(property "Author" "Antmicro"
			(at 0 0 0)
			(unlocked yes)
			(layer "B.Fab")
			(hide yes)
			(effects
				(font
					(size 1 1)
					(thickness 0.15)
				)
				(justify mirror)
			)
		)
		(sheetname "/2xRJ45/")
		(sheetfile "2xrj45.kicad_sch")
		(attr smd)
		(fp_rect
			(start -0.925 0.47)
			(end 0.925 -0.47)
			(stroke
				(width 0.05)
				(type default)
			)
			(fill no)
			(layer "B.CrtYd")
		)
		(fp_line
			(start -0.494 -0.248)
			(end -0.494 0.25)
			(stroke
				(width 0.15)
				(type solid)
			)
			(layer "B.Fab")
		)
		(fp_line
			(start -0.494 0.25)
			(end 0.504 0.25)
			(stroke
				(width 0.15)
				(type solid)
			)
			(layer "B.Fab")
		)
		(fp_line
			(start 0.504 -0.248)
			(end -0.494 -0.248)
			(stroke
				(width 0.15)
				(type solid)
			)
			(layer "B.Fab")
		)
		(fp_line
			(start 0.504 0.25)
			(end 0.504 -0.248)
			(stroke
				(width 0.15)
				(type solid)
			)
			(layer "B.Fab")
		)
		(pad "1" smd roundrect
			(at -0.48 0)
			(size 0.59 0.64)
			(layers "B.Cu" "B.Mask" "B.Paste")
			(roundrect_rratio 0.25)
			(net 28 "GND")
			(pintype "passive")
		)
		(pad "2" smd roundrect
			(at 0.48 0)
			(size 0.59 0.64)
			(layers "B.Cu" "B.Mask" "B.Paste")
			(roundrect_rratio 0.25)
			(net 18 "+1V88")
			(pintype "passive")
		)
	)
	(footprint "antmicro-footprints:C_0402_1005Metric"
		(layer "B.Cu")
		(at 86.225 98.3 90)
		(descr "Capacitor SMD 0402")
		(tags "capacitor SMD 0402")
		(property "Reference" "C115"
			(at 10.69 -0.536429 90)
			(layer "B.SilkS")
			(effects
				(font
					(size 0.7 0.7)
					(thickness 0.15)
				)
				(justify right top mirror)
			)
		)
		(property "Value" "C_1u_25V_0402"
			(at -1.022927 -2.155213 90)
			(layer "B.Fab")
			(hide yes)
			(effects
				(font
					(size 0.7 0.7)
					(thickness 0.15)
				)
				(justify right top mirror)
			)
		)
		(property "Datasheet" "https://www.murata.com/products/productdetail?partno=GRM155R61E105KE11%23"
			(at 0 0 90)
			(layer "B.Fab")
			(hide yes)
			(effects
				(font
					(size 1.27 1.27)
					(thickness 0.15)
				)
				(justify mirror)
			)
		)
		(property "Description" "SMD Multilayer Ceramic Capacitor, 1 µF, 25 V, 0402 [1005 Metric], ± 10%, X5R, GRM Series"
			(at 0 0 90)
			(layer "B.Fab")
			(hide yes)
			(effects
				(font
					(size 1.27 1.27)
					(thickness 0.15)
				)
				(justify mirror)
			)
		)
		(property "MPN" "GRM155R61E105KE11J"
			(at 0 0 90)
			(unlocked yes)
			(layer "B.Fab")
			(hide yes)
			(effects
				(font
					(size 1 1)
					(thickness 0.15)
				)
				(justify mirror)
			)
		)
		(property "Manufacturer" "Murata"
			(at 0 0 90)
			(unlocked yes)
			(layer "B.Fab")
			(hide yes)
			(effects
				(font
					(size 1 1)
					(thickness 0.15)
				)
				(justify mirror)
			)
		)
		(property "License" "Apache-2.0"
			(at 0 0 90)
			(unlocked yes)
			(layer "B.Fab")
			(hide yes)
			(effects
				(font
					(size 1 1)
					(thickness 0.15)
				)
				(justify mirror)
			)
		)
		(property "Author" "Antmicro"
			(at 0 0 90)
			(unlocked yes)
			(layer "B.Fab")
			(hide yes)
			(effects
				(font
					(size 1 1)
					(thickness 0.15)
				)
				(justify mirror)
			)
		)
		(property "Val" "1u"
			(at 0 0 90)
			(unlocked yes)
			(layer "B.Fab")
			(hide yes)
			(effects
				(font
					(size 1 1)
					(thickness 0.15)
				)
				(justify mirror)
			)
		)
		(property "Voltage" "25V"
			(at 0 0 90)
			(unlocked yes)
			(layer "B.Fab")
			(hide yes)
			(effects
				(font
					(size 1 1)
					(thickness 0.15)
				)
				(justify mirror)
			)
		)
		(property "Dielectric" "X5R"
			(at 0 0 90)
			(unlocked yes)
			(layer "B.Fab")
			(hide yes)
			(effects
				(font
					(size 1 1)
					(thickness 0.15)
				)
				(justify mirror)
			)
		)
		(sheetname "/X710-AT2 power/")
		(sheetfile "x710-at2-power.kicad_sch")
		(attr smd)
		(fp_rect
			(start -0.925 0.47)
			(end 0.925 -0.47)
			(stroke
				(width 0.05)
				(type default)
			)
			(fill no)
			(layer "B.CrtYd")
		)
		(fp_line
			(start 0.504 -0.248)
			(end -0.494 -0.248)
			(stroke
				(width 0.15)
				(type solid)
			)
			(layer "B.Fab")
		)
		(fp_line
			(start -0.494 -0.248)
			(end -0.494 0.25)
			(stroke
				(width 0.15)
				(type solid)
			)
			(layer "B.Fab")
		)
		(fp_line
			(start 0.504 0.25)
			(end 0.504 -0.248)
			(stroke
				(width 0.15)
				(type solid)
			)
			(layer "B.Fab")
		)
		(fp_line
			(start -0.494 0.25)
			(end 0.504 0.25)
			(stroke
				(width 0.15)
				(type solid)
			)
			(layer "B.Fab")
		)
		(pad "1" smd roundrect
			(at -0.48 0 90)
			(size 0.59 0.64)
			(layers "B.Cu" "B.Mask" "B.Paste")
			(roundrect_rratio 0.25)
			(net 28 "GND")
			(pintype "passive")
		)
		(pad "2" smd roundrect
			(at 0.48 0 90)
			(size 0.59 0.64)
			(layers "B.Cu" "B.Mask" "B.Paste")
			(roundrect_rratio 0.25)
			(net 9 "VCCD")
			(pintype "passive")
		)
	)
	(footprint "antmicro-footprints:C_0402_1005Metric"
		(layer "B.Cu")
		(at 71.48 145.34 -90)
		(descr "Capacitor SMD 0402")
		(tags "capacitor SMD 0402")
		(property "Reference" "C50"
			(at -2.92 -0.45 90)
			(layer "B.SilkS")
			(effects
				(font
					(size 0.7 0.7)
					(thickness 0.15)
				)
				(justify left bottom mirror)
			)
		)
		(property "Value" "C_470p_0402"
			(at -1.022927 -2.155213 90)
			(layer "B.Fab")
			(hide yes)
			(effects
				(font
					(size 0.7 0.7)
					(thickness 0.15)
				)
				(justify left bottom mirror)
			)
		)
		(property "Datasheet" "https://www.passivecomponent.com/wp-content/uploads/datasheet/WTC_MLCC_General_Purpose.pdf"
			(at 0 0 90)
			(layer "B.Fab")
			(hide yes)
			(effects
				(font
					(size 1.27 1.27)
					(thickness 0.15)
				)
				(justify mirror)
			)
		)
		(property "Description" "SMD Multilayer Ceramic Capacitor, General Purpose, 470 pF, 25 V, 0402 [1005 Metric], ± 10%, X7R"
			(at 0 0 90)
			(layer "B.Fab")
			(hide yes)
			(effects
				(font
					(size 1.27 1.27)
					(thickness 0.15)
				)
				(justify mirror)
			)
		)
		(property "MPN" "0402B471K250CT"
			(at 0 0 270)
			(unlocked yes)
			(layer "B.Fab")
			(hide yes)
			(effects
				(font
					(size 1 1)
					(thickness 0.15)
				)
				(justify mirror)
			)
		)
		(property "Manufacturer" "Walsin"
			(at 0 0 270)
			(unlocked yes)
			(layer "B.Fab")
			(hide yes)
			(effects
				(font
					(size 1 1)
					(thickness 0.15)
				)
				(justify mirror)
			)
		)
		(property "License" "Apache-2.0"
			(at 0 0 270)
			(unlocked yes)
			(layer "B.Fab")
			(hide yes)
			(effects
				(font
					(size 1 1)
					(thickness 0.15)
				)
				(justify mirror)
			)
		)
		(property "Author" "Antmicro"
			(at 0 0 270)
			(unlocked yes)
			(layer "B.Fab")
			(hide yes)
			(effects
				(font
					(size 1 1)
					(thickness 0.15)
				)
				(justify mirror)
			)
		)
		(property "Val" "470p"
			(at 0 0 270)
			(unlocked yes)
			(layer "B.Fab")
			(hide yes)
			(effects
				(font
					(size 1 1)
					(thickness 0.15)
				)
				(justify mirror)
			)
		)
		(property "Voltage" "25V"
			(at 0 0 270)
			(unlocked yes)
			(layer "B.Fab")
			(hide yes)
			(effects
				(font
					(size 1 1)
					(thickness 0.15)
				)
				(justify mirror)
			)
		)
		(property "Dielectric" "X7R"
			(at 0 0 270)
			(unlocked yes)
			(layer "B.Fab")
			(hide yes)
			(effects
				(font
					(size 1 1)
					(thickness 0.15)
				)
				(justify mirror)
			)
		)
		(sheetname "/2xRJ45/")
		(sheetfile "2xrj45.kicad_sch")
		(attr smd)
		(fp_rect
			(start -0.925 0.47)
			(end 0.925 -0.47)
			(stroke
				(width 0.05)
				(type default)
			)
			(fill no)
			(layer "B.CrtYd")
		)
		(fp_line
			(start -0.494 0.25)
			(end 0.504 0.25)
			(stroke
				(width 0.15)
				(type solid)
			)
			(layer "B.Fab")
		)
		(fp_line
			(start 0.504 0.25)
			(end 0.504 -0.248)
			(stroke
				(width 0.15)
				(type solid)
			)
			(layer "B.Fab")
		)
		(fp_line
			(start -0.494 -0.248)
			(end -0.494 0.25)
			(stroke
				(width 0.15)
				(type solid)
			)
			(layer "B.Fab")
		)
		(fp_line
			(start 0.504 -0.248)
			(end -0.494 -0.248)
			(stroke
				(width 0.15)
				(type solid)
			)
			(layer "B.Fab")
		)
		(pad "1" smd roundrect
			(at -0.48 0 270)
			(size 0.59 0.64)
			(layers "B.Cu" "B.Mask" "B.Paste")
			(roundrect_rratio 0.25)
			(net 28 "GND")
			(pintype "passive")
		)
		(pad "2" smd roundrect
			(at 0.48 0 270)
			(size 0.59 0.64)
			(layers "B.Cu" "B.Mask" "B.Paste")
			(roundrect_rratio 0.25)
			(net 54 "Net-(J3-LED_GRN-)")
			(pintype "passive")
		)
	)
)
